# BARRELEYE_G2-BPX24-EVT-HW-EBOM-X00_20161124-add_2nd_source_X09-20161207-Final.xls — Changelist (bom)
| BOM Change List Date:Wed Dec 07 15:51:21 GMT+08:00 2016 |  |  |  |  |  |  |  |  |  |
| New BOM file :BARRELEYE_G2-BPX24-EVT-HW-EBOM-X00_20161124-add 2nd source_X09-20161207-final.xls |  |  |  |  |  |  |  |  |  |
| Old BOM file : BARRELEYE_G2-BPX24-EVT-HW-EBOM-X00_20161124-add 2nd source_X08-20161124.xls |  |  |  |  |  |  |  |  |  |
| ##### Add Parts |  |  |  |  |  |  |  |  |  |
| Item | Location | Qty | Foxconn P/N | Part Description | Manufacturer Full Name | Manufacturer P/N | RoHS | Sheet |  |
| ##### Remove Parts |  |  |  |  |  |  |  |  |  |
| Item | Location | Qty | Foxconn P/N | Part Description | Manufacturer Full Name | Manufacturer P/N | RoHS | Sheet |  |
| 1 | PSTR4,PFTR4,PETR4 | 3 | 61011HA00-017-G | RES,1 Ohm,+/-1%,1/16W,G,SMD0402 | KOA SPEER ELECTRONICS, INC. | RK73H1ETTP1R00F |  | PWA BOM |  |
|  |  |  | 61011HA00-012-G | RES,1 Ohm,+/-1%,1/16W,G,SMD0402 | WALSIN TECHNOLOGY CORPORATION | WR04W1R00FTL |  | PWA BOM |  |
|  |  |  | 61011HA00-011-G | RES,1 Ohm,+/-1%,1/16W,G,SMD0402 | YAGEO CORPORATION COMPONENT | RC0402FR-071RL |  | PWA BOM |  |
|  |  |  | 61011HA00-044-G | RES,1 Ohm,+/-1%,1/16W,G,SMD0402 | TA-I TECHNOLOGY CO., LTD | RM04FTN1R00 |  | PWA BOM |  |
|  |  |  | 61011HA00-029-G | RES,1 Ohm,+/-1%,1/16W,G,SMD0402 | VISHAY ENTER TECHNO LOGY.INC | CRCW04021R00FNED |  | PWA BOM |  |
| 2 | PSTC5,PFTC5,PETC5 | 3 | 62010L800-015-G | CAP,1nF,+/-5%,NPO(C0G),50V,G,SMD0402 | MURATA ELEC. NORTH AMERICA | GRM1555C1H102J |  | PWA BOM |  |
|  |  |  | 62010L800-012-G | CAP,1nF,+/-5%,NPO(C0G),50V,G,SMD0402 | WALSIN TECHNOLOGY CORPORATION | 0402N102J500CT |  | PWA BOM |  |
|  |  |  | 62010L800-026-G | CAP,1nF,+/-5%,NPO(C0G),50V,G,SMD0402 | SAMSUNG SEMICONDUCTOR | CL05C102JB5NNNC |  | PWA BOM |  |
| ##### Change Parts |  |  |  |  |  |  |  |  |  |
| Item | Location | Qty | Foxconn P/N | Part Description | Manufacturer Full Name | Manufacturer P/N | RoHS | Sheet | Remark |
| 1 | PSRC3,PSTC3004,PFTC3004,PETC3004,PSTC3009,PFTC3009,PETC3009 | 7 | 62012GG00-015-G | CAP,10uF,+/-10%,X7S,25V,G,SMD0805 | MURATA ELEC. NORTH AMERICA | GRM21BC71E106K |  | PWA BOM | In New BOM |
|  |  |  | 62012GG00-012-G | CAP,10uF,+/-10%,X7S,25V,G,SMD0805 | WALSIN | 0805A106K250CT |  | PWA BOM | In New BOM |
|  | PSRC3,PSTC3004,PFTC3004,PETC3004,PSTC3009,PFTC3009,PETC3009 | 7 | 62012GG00-015-G | CAP,10uF,+/-10%,X7S,25V,G,SMD0805 | MURATA ELEC. NORTH AMERICA | GRM21BC71E106K |  | PWA BOM | In Old BOM |
| 2 | PSRC5 | 1 | 62012P100-015-G | CAP,2.2uF,+/-20%,X7S,10V,G,SMD0402 | MURATA ELEC. NORTH AMERICA | GRM155C71A225M |  | PWA BOM | In New BOM |
|  |  |  | 62012P100-012-G | CAP,2.2uF,+/-20%,X7S,10V,G,SMD0402 | WALSIN | 0402A225M100CT |  | PWA BOM | In New BOM |
|  | PSRC5 | 1 | 62012P100-015-G | CAP,2.2uF,+/-20%,X7S,10V,G,SMD0402 | MURATA ELEC. NORTH AMERICA | GRM155C71A225M |  | PWA BOM | In Old BOM |
| ##### Change Revision |  |  |  |  |  |  |  |  |  |
| Sheet | REV OF BOM | CUSTOMER | CUSTOMER P/N | PWA PN | PWA DESCRIPTION | PWA REV | DATE | Remark |  |
| PWA BOM | X09 | RACKSPACE |  |  |  |  |  | In New BOM |  |
| PWA BOM | X08 | RACKSPACE |  |  |  |  |  | In Old BOM |  |
| OOOOOOOOOOOOOOOOOOOOOOOOOOOOOOOOOOOOOOOOOOOOOOOOOOOOOOOOOOOOOOOOOOOOOOOOOOOOOOOOOOOOOOOOOO | OOOOOOOOOOOOOOOOOOOOOOOOOOOOOOOOOOOOOOOOOOOOOOOOOOOOOOOOOOOOOOOOOOOOOOOOOOOOOOOOOOOOOOOOOO | OOOOOOOOOOOOOOOOOOOOOOOOOOOOOOOOOOOOOOOOOOOOOOOOOOOOOOOOOOOOOOOOOOOOOOOOOOOOOOOOOOOOOOOOOO | OOOOOOOOOOOOOOOOOOOOOOOOOOOOOOOOOOOOOOOOOOOOOOOOOOOOOOOOOOOOOOOOOOOOOOOOOOOOOOOOOOOOOOOOOO | OOOOOOOOOOOOOOOOOOOOOOOOOOOOOOOOOOOOOOOOOOOOOOOOOOOOOOOOOOOOOOOOOOOOOOOOOOOOOOOOOOOOOOOOOO | OOOOOOOOOOOOOOOOOOOOOOOOOOOOOOOOOOOOOOOOOOOOOOOOOOOOOOOOOOOOOOOOOOOOOOOOOOOOOOOOOOOOOOOOOO | OOOOOOOOOOOOOOOOOOOOOOOOOOOOOOOOOOOOOOOOOOOOOOOOOOOOOOOOOOOOOOOOOOOOOOOOOOOOOOOOOOOOOOOOOO | OOOOOOOOOOOOOOOOOOOOOOOOOOOOOOOOOOOOOOOOOOOOOOOOOOOOOOOOOOOOOOOOOOOOOOOOOOOOOOOOOOOOOOOOOO | OOOOOOOOOOOOOOOOOOOOOOOOOOOOOOOOOOOOOOOOOOOOOOOOOOOOOOOOOOOOOOOOOOOOOOOOOOOOOOOOOOOOOOOOOO | OOOOOOOOOOOOOOOOOOOOOOOOOOOOOOOOOOOOOOOOOOOOOOOOOOOOOOOOOOOOOOOOOOOOOOOOOOOOOOOOOOOOOOOOOO |
| Second Source Change |  |  |  |  |  |  |  |  |  |
| Item | Location | Change Type | Foxconn P/N | Part Description | Manufacturer Full Name | Manufacturer P/N | RoHS | Sheet |  |
| 1 | PSRC3,PSTC3004,PFTC3004,PETC3004,PSTC3009,PFTC3009,PETC3009 |  | 62012GG00-015-G | CAP,10uF,+/-10%,X7S,25V,G,SMD0805 | MURATA ELEC. NORTH AMERICA | GRM21BC71E106K |  | PWA BOM |  |
|  |  | ADD | 62012GG00-012-G | CAP,10uF,+/-10%,X7S,25V,G,SMD0805 | WALSIN | 0805A106K250CT |  | PWA BOM |  |
| 2 | PSRC5 |  | 62012P100-015-G | CAP,2.2uF,+/-20%,X7S,10V,G,SMD0402 | MURATA ELEC. NORTH AMERICA | GRM155C71A225M |  | PWA BOM |  |
|  |  | ADD | 62012P100-012-G | CAP,2.2uF,+/-20%,X7S,10V,G,SMD0402 | WALSIN | 0402A225M100CT |  | PWA BOM |  |
| OOOOOOOOOOOOOOOOOOOOOOOOOOOOOOOOOOOOOOOOOOOOOOOOOOOOOOOOOOOOOOOOOOOOOOOOOOOOOOOOOOOOOOOOOO | OOOOOOOOOOOOOOOOOOOOOOOOOOOOOOOOOOOOOOOOOOOOOOOOOOOOOOOOOOOOOOOOOOOOOOOOOOOOOOOOOOOOOOOOOO | OOOOOOOOOOOOOOOOOOOOOOOOOOOOOOOOOOOOOOOOOOOOOOOOOOOOOOOOOOOOOOOOOOOOOOOOOOOOOOOOOOOOOOOOOO | OOOOOOOOOOOOOOOOOOOOOOOOOOOOOOOOOOOOOOOOOOOOOOOOOOOOOOOOOOOOOOOOOOOOOOOOOOOOOOOOOOOOOOOOOO | OOOOOOOOOOOOOOOOOOOOOOOOOOOOOOOOOOOOOOOOOOOOOOOOOOOOOOOOOOOOOOOOOOOOOOOOOOOOOOOOOOOOOOOOOO | OOOOOOOOOOOOOOOOOOOOOOOOOOOOOOOOOOOOOOOOOOOOOOOOOOOOOOOOOOOOOOOOOOOOOOOOOOOOOOOOOOOOOOOOOO | OOOOOOOOOOOOOOOOOOOOOOOOOOOOOOOOOOOOOOOOOOOOOOOOOOOOOOOOOOOOOOOOOOOOOOOOOOOOOOOOOOOOOOOOOO | OOOOOOOOOOOOOOOOOOOOOOOOOOOOOOOOOOOOOOOOOOOOOOOOOOOOOOOOOOOOOOOOOOOOOOOOOOOOOOOOOOOOOOOOOO | OOOOOOOOOOOOOOOOOOOOOOOOOOOOOOOOOOOOOOOOOOOOOOOOOOOOOOOOOOOOOOOOOOOOOOOOOOOOOOOOOOOOOOOOOO | OOOOOOOOOOOOOOOOOOOOOOOOOOOOOOOOOOOOOOOOOOOOOOOOOOOOOOOOOOOOOOOOOOOOOOOOOOOOOOOOOOOOOOOOOO |
| Master Materials Change |  |  |  |  |  |  |  |  |  |
| Item | Foxconn P/N | Orig._Usage | New_Usage | Part Description | Manufacturer Full Name | Manufacturer P/N | RoHS | Location | Sheet |
| 1 | 61011HA00-017-G | 4 | 1 | RES,1 Ohm,+/-1%,1/16W,G,SMD0402 | KOA SPEER ELECTRONICS, INC. | RK73H1ETTP1R00F |  | (-)PSTR4,PFTR4,PETR4 | PWA BOM |
|  | 61011HA00-012-G |  |  | RES,1 Ohm,+/-1%,1/16W,G,SMD0402 | WALSIN TECHNOLOGY CORPORATION | WR04W1R00FTL |  |  | PWA BOM |
|  | 61011HA00-011-G |  |  | RES,1 Ohm,+/-1%,1/16W,G,SMD0402 | YAGEO CORPORATION COMPONENT | RC0402FR-071RL |  |  | PWA BOM |
|  | 61011HA00-044-G |  |  | RES,1 Ohm,+/-1%,1/16W,G,SMD0402 | TA-I TECHNOLOGY CO., LTD | RM04FTN1R00 |  |  | PWA BOM |
|  | 61011HA00-029-G |  |  | RES,1 Ohm,+/-1%,1/16W,G,SMD0402 | VISHAY ENTER TECHNO LOGY.INC | CRCW04021R00FNED |  |  | PWA BOM |
| 2 | 62010L800-015-G | 3 | 0 | CAP,1nF,+/-5%,NPO(C0G),50V,G,SMD0402 | MURATA ELEC. NORTH AMERICA | GRM1555C1H102J |  | (-)PSTC5,PFTC5,PETC5 | PWA BOM |
|  | 62010L800-012-G |  |  | CAP,1nF,+/-5%,NPO(C0G),50V,G,SMD0402 | WALSIN TECHNOLOGY CORPORATION | 0402N102J500CT |  |  | PWA BOM |
|  | 62010L800-026-G |  |  | CAP,1nF,+/-5%,NPO(C0G),50V,G,SMD0402 | SAMSUNG SEMICONDUCTOR | CL05C102JB5NNNC |  |  | PWA BOM |
| OOOOOOOOOOOOOOOOOOOOOOOOOOOOOOOOOOOOOOOOOOOOOOOOOOOOOOOOOOOOOOOOOOOOOOOOOOOOOOOOOOOOOOOOOO | OOOOOOOOOOOOOOOOOOOOOOOOOOOOOOOOOOOOOOOOOOOOOOOOOOOOOOOOOOOOOOOOOOOOOOOOOOOOOOOOOOOOOOOOOO | OOOOOOOOOOOOOOOOOOOOOOOOOOOOOOOOOOOOOOOOOOOOOOOOOOOOOOOOOOOOOOOOOOOOOOOOOOOOOOOOOOOOOOOOOO | OOOOOOOOOOOOOOOOOOOOOOOOOOOOOOOOOOOOOOOOOOOOOOOOOOOOOOOOOOOOOOOOOOOOOOOOOOOOOOOOOOOOOOOOOO | OOOOOOOOOOOOOOOOOOOOOOOOOOOOOOOOOOOOOOOOOOOOOOOOOOOOOOOOOOOOOOOOOOOOOOOOOOOOOOOOOOOOOOOOOO | OOOOOOOOOOOOOOOOOOOOOOOOOOOOOOOOOOOOOOOOOOOOOOOOOOOOOOOOOOOOOOOOOOOOOOOOOOOOOOOOOOOOOOOOOO | OOOOOOOOOOOOOOOOOOOOOOOOOOOOOOOOOOOOOOOOOOOOOOOOOOOOOOOOOOOOOOOOOOOOOOOOOOOOOOOOOOOOOOOOOO | OOOOOOOOOOOOOOOOOOOOOOOOOOOOOOOOOOOOOOOOOOOOOOOOOOOOOOOOOOOOOOOOOOOOOOOOOOOOOOOOOOOOOOOOOO | OOOOOOOOOOOOOOOOOOOOOOOOOOOOOOOOOOOOOOOOOOOOOOOOOOOOOOOOOOOOOOOOOOOOOOOOOOOOOOOOOOOOOOOOOO |  |
| TLA Parts Change |  |  |  |  |  |  |  |  |  |
| Item | Foxconn P/N | Qty | Part Description | Manufacturer Full Name | Manufacturer P/N | RoHS | Location | Remark |  |
